#ISCELL
  mstr_symbols intel_corp_bpage *
  *
#ISCELL
  mstr_standard offpage *
  page129_i1
#ISCELL
  mstr_standard offpage *
  page129_i10
#ISCELL
  mstr_standard tap *
  page129_i11
#ISCELL
  mstr_standard tap *
  page129_i12
#ISCELL
  mstr_standard tap *
  page129_i13
#ISCELL
  mstr_standard tap *
  page129_i14
#ISCELL
  mstr_standard tap *
  page129_i2
#ISCELL
  mstr_standard tap *
  page129_i23
#ISCELL
  mstr_standard tap *
  page129_i24
#ISCELL
  mstr_standard tap *
  page129_i25
#ISCELL
  mstr_standard tap *
  page129_i26
#ISCELL
  mstr_standard offpage *
  page129_i27
#ISCELL
  mstr_standard offpage *
  page129_i28
#ISCELL
  mstr_standard tap *
  page129_i29
#ISCELL
  mstr_standard tap *
  page129_i3
#ISCELL
  mstr_standard tap *
  page129_i30
#ISCELL
  mstr_standard tap *
  page129_i31
#ISCELL
  mstr_standard tap *
  page129_i32
#CELL
  mstr_discrete cap *
  page129_i35
#ISCELL
  mstr_standard tap *
  page129_i37
#ISCELL
  mstr_standard tap *
  page129_i38
#ISCELL
  mstr_standard tap *
  page129_i39
#ISCELL
  mstr_standard tap *
  page129_i4
#ISCELL
  mstr_standard tap *
  page129_i40
#ISCELL
  mstr_standard offpage *
  page129_i42
#ISCELL
  mstr_standard offpage *
  page129_i43
#ISCELL
  mstr_standard tap *
  page129_i45
#ISCELL
  mstr_standard tap *
  page129_i46
#ISCELL
  mstr_standard tap *
  page129_i47
#ISCELL
  mstr_standard tap *
  page129_i48
#ISCELL
  mstr_standard tap *
  page129_i5
#ISCELL
  mstr_standard tap *
  page129_i57
#ISCELL
  mstr_standard tap *
  page129_i58
#ISCELL
  mstr_standard tap *
  page129_i59
#ISCELL
  mstr_standard tap *
  page129_i60
#ISCELL
  mstr_standard offpage *
  page129_i61
#ISCELL
  mstr_standard tap *
  page129_i62
#ISCELL
  mstr_standard tap *
  page129_i63
#ISCELL
  mstr_standard tap *
  page129_i64
#ISCELL
  mstr_standard tap *
  page129_i65
#ISCELL
  mstr_standard offpage *
  page129_i67
#CELL
  mstr_discrete cap *
  page129_i69
#CELL
  mstr_discrete cap *
  page129_i70
#CELL
  mstr_discrete cap *
  page129_i71
#CELL
  mstr_discrete cap *
  page129_i72
#CELL
  mstr_discrete cap *
  page129_i73
#CELL
  mstr_discrete cap *
  page129_i74
#CELL
  mstr_discrete cap *
  page129_i75
#CELL
  mstr_discrete cap *
  page129_i76
#CELL
  mstr_discrete cap *
  page129_i77
#CELL
  mstr_discrete cap *
  page129_i78
#CELL
  mstr_discrete cap *
  page129_i79
#CELL
  mstr_discrete cap *
  page129_i80
#CELL
  mstr_discrete cap *
  page129_i81
#CELL
  mstr_discrete cap *
  page129_i82
#CELL
  mstr_discrete cap *
  page129_i83
